(kicad_pcb
	(version 20260206)
	(generator "pcbnew")
	(generator_version "10.0")
	(general
		(thickness 1.6)
		(legacy_teardrops no)
	)
	(paper "A4")
	(title_block
		(title "baseboard — 13948-1b.1110WZS1818.brd")
		(comment 1 "Honey Badger (Wiwynn) / footprints 148-154 of 2523")
	)
	(layers
		(0 "F.Cu" signal "TOP")
		(4 "In1.Cu" signal "L2GND")
		(6 "In2.Cu" signal "L3")
		(8 "In3.Cu" signal "L4VCC")
		(10 "In4.Cu" signal "L5VCC")
		(12 "In5.Cu" signal "L6")
		(14 "In6.Cu" signal "L7GND")
		(2 "B.Cu" signal "BOTTOM")
		(9 "F.Adhes" user "F.Adhesive")
		(11 "B.Adhes" user "B.Adhesive")
		(13 "F.Paste" user "Package Geometry/Pastemask Top")
		(15 "B.Paste" user "Package Geometry/Pastemask Bottom")
		(5 "F.SilkS" user "Ref Des/Silkscreen Top")
		(7 "B.SilkS" user "Ref Des/Silkscreen Bottom")
		(1 "F.Mask" user "Board Geometry/Soldermask Top")
		(3 "B.Mask" user "Board Geometry/Soldermask Bottom")
		(17 "Dwgs.User" user "User.Drawings")
		(19 "Cmts.User" user "User.Comments")
		(21 "Eco1.User" user "User.Eco1")
		(23 "Eco2.User" user "User.Eco2")
		(25 "Edge.Cuts" user "Board Geometry/Outline")
		(27 "Margin" user)
		(31 "F.CrtYd" user "Package Geometry/Place Bound Top")
		(29 "B.CrtYd" user "Package Geometry/Place Bound Bottom")
		(35 "F.Fab" user "Ref Des/Assembly Top")
		(33 "B.Fab" user "Ref Des/Assembly Bottom")
	)
	(footprint ""
		(layer "F.Cu")
		(at 274.193 -172.593 90)
		(property "Reference" "R365"
			(at 0 0 90)
			(layer "F.SilkS")
			(hide yes)
			(effects
				(font
					(size 1.27 1.27)
				)
			)
		)
		(property "Value" "3K3R2F-2-GP"
			(at 0.064008 -3.993896 90)
			(unlocked yes)
			(layer "F.Fab")
			(hide yes)
			(effects
				(font
					(size 1.016 1.016)
					(thickness 0.1524)
				)
			)
		)
		(property "Device Type" "R402H16"
			(at 0.064008 -5.517896 90)
			(unlocked yes)
			(layer "F.Fab")
			(hide yes)
			(effects
				(font
					(size 1.016 1.016)
					(thickness 0.1524)
				)
			)
		)
		(duplicate_pad_numbers_are_jumpers no)
		(fp_line
			(start 0.508 -0.9398)
			(end -0.508 -0.9398)
			(stroke
				(width 0.1524)
				(type default)
			)
			(layer "F.SilkS")
		)
		(fp_line
			(start -0.508 -0.9398)
			(end -0.508 0.9398)
			(stroke
				(width 0.1524)
				(type default)
			)
			(layer "F.SilkS")
		)
		(fp_rect
			(start -0.508 0.9398)
			(end 0.508 -0.9398)
			(stroke
				(width 0)
				(type default)
			)
			(fill no)
			(layer "F.CrtYd")
		)
		(fp_rect
			(start -0.508 0.9398)
			(end 0.508 -0.9398)
			(stroke
				(width 0)
				(type default)
			)
			(fill no)
			(layer "F.Fab")
		)
		(pad "1" smd custom
			(at 0 -0.4445 90)
			(size 0.1397 0.1397)
			(layers "F.Cu" "F.Mask" "F.Paste")
			(net "P3V3_STBY")
			(options
				(clearance outline)
				(anchor circle)
			)
			(primitives
				(gr_poly
					(pts
						(arc
							(start -0.1778 -0.2794)
							(mid -0.249642 -0.249642)
							(end -0.2794 -0.1778)
						)
						(arc
							(start -0.2794 0.1778)
							(mid -0.249642 0.249642)
							(end -0.1778 0.2794)
						)
						(arc
							(start 0.1778 0.2794)
							(mid 0.249642 0.249642)
							(end 0.2794 0.1778)
						)
						(arc
							(start 0.2794 -0.1778)
							(mid 0.249642 -0.249642)
							(end 0.1778 -0.2794)
						)
					)
					(width 0)
					(fill yes)
				)
			)
		)
		(pad "2" smd custom
			(at 0 0.4445 90)
			(size 0.1397 0.1397)
			(layers "F.Cu" "F.Mask" "F.Paste")
			(net "ROMA22")
			(options
				(clearance outline)
				(anchor circle)
			)
			(primitives
				(gr_poly
					(pts
						(arc
							(start -0.1778 -0.2794)
							(mid -0.249642 -0.249642)
							(end -0.2794 -0.1778)
						)
						(arc
							(start -0.2794 0.1778)
							(mid -0.249642 0.249642)
							(end -0.1778 0.2794)
						)
						(arc
							(start 0.1778 0.2794)
							(mid 0.249642 0.249642)
							(end 0.2794 0.1778)
						)
						(arc
							(start 0.2794 -0.1778)
							(mid 0.249642 -0.249642)
							(end 0.1778 -0.2794)
						)
					)
					(width 0)
					(fill yes)
				)
			)
		)
	)
	(footprint ""
		(layer "F.Cu")
		(at 292.165532 -191.819276)
		(property "Reference" "C175"
			(at 0 0 0)
			(layer "F.SilkS")
			(hide yes)
			(effects
				(font
					(size 1.27 1.27)
				)
			)
		)
		(property "Value" "SCD1U16V2KX-3GP"
			(at 1.1811 -2.7051 0)
			(unlocked yes)
			(layer "F.Fab")
			(hide yes)
			(effects
				(font
					(size 1.016 1.016)
					(thickness 0.1524)
				)
			)
		)
		(property "Device Type" "C402H22"
			(at 1.1811 -4.2291 0)
			(unlocked yes)
			(layer "F.Fab")
			(hide yes)
			(effects
				(font
					(size 1.016 1.016)
					(thickness 0.1524)
				)
			)
		)
		(duplicate_pad_numbers_are_jumpers no)
		(fp_rect
			(start -0.4318 0.9525)
			(end 0.4318 -0.9525)
			(stroke
				(width 0)
				(type default)
			)
			(fill no)
			(layer "F.CrtYd")
		)
		(fp_rect
			(start -0.4318 0.9525)
			(end 0.4318 -0.9525)
			(stroke
				(width 0)
				(type default)
			)
			(fill no)
			(layer "F.Fab")
		)
		(pad "1" smd custom
			(at 0 -0.4445)
			(size 0.1524 0.1524)
			(layers "F.Cu" "F.Mask" "F.Paste")
			(net "P1V53_STBY")
			(options
				(clearance outline)
				(anchor circle)
			)
			(primitives
				(gr_poly
					(pts
						(arc
							(start 0.3048 -0.2032)
							(mid 0.275042 -0.275042)
							(end 0.2032 -0.3048)
						)
						(arc
							(start -0.2032 -0.3048)
							(mid -0.275042 -0.275042)
							(end -0.3048 -0.2032)
						)
						(arc
							(start -0.3048 0.2032)
							(mid -0.275042 0.275042)
							(end -0.2032 0.3048)
						)
						(arc
							(start 0.2032 0.3048)
							(mid 0.275042 0.275042)
							(end 0.3048 0.2032)
						)
					)
					(width 0)
					(fill yes)
				)
			)
		)
		(pad "2" smd custom
			(at 0 0.4445)
			(size 0.1524 0.1524)
			(layers "F.Cu" "F.Mask" "F.Paste")
			(net "GND")
			(options
				(clearance outline)
				(anchor circle)
			)
			(primitives
				(gr_poly
					(pts
						(arc
							(start 0.3048 -0.2032)
							(mid 0.275042 -0.275042)
							(end 0.2032 -0.3048)
						)
						(arc
							(start -0.2032 -0.3048)
							(mid -0.275042 -0.275042)
							(end -0.3048 -0.2032)
						)
						(arc
							(start -0.3048 0.2032)
							(mid -0.275042 0.275042)
							(end -0.2032 0.3048)
						)
						(arc
							(start 0.2032 0.3048)
							(mid 0.275042 0.275042)
							(end 0.3048 0.2032)
						)
					)
					(width 0)
					(fill yes)
				)
			)
		)
	)
	(footprint ""
		(layer "F.Cu")
		(at 119.52097 -114.3 180)
		(property "Reference" "SC1070"
			(at 0 0 180)
			(layer "F.SilkS")
			(hide yes)
			(effects
				(font
					(size 1.27 1.27)
				)
			)
		)
		(property "Value" "SCD01U10V1KX-GP"
			(at -2.8321 -1.7399 180)
			(unlocked yes)
			(layer "F.Fab")
			(hide yes)
			(effects
				(font
					(size 1.016 1.016)
					(thickness 0.1524)
				)
			)
		)
		(property "Device Type" "C0201H13"
			(at -2.8321 -3.2639 180)
			(unlocked yes)
			(layer "F.Fab")
			(hide yes)
			(effects
				(font
					(size 1.016 1.016)
					(thickness 0.1524)
				)
			)
		)
		(duplicate_pad_numbers_are_jumpers no)
		(fp_rect
			(start -0.2794 0.6477)
			(end 0.2794 -0.6477)
			(stroke
				(width 0)
				(type default)
			)
			(fill no)
			(layer "F.CrtYd")
		)
		(fp_rect
			(start -0.2794 0.6477)
			(end 0.2794 -0.6477)
			(stroke
				(width 0)
				(type default)
			)
			(fill no)
			(layer "F.Fab")
		)
		(pad "1" smd custom
			(at 0 -0.2794 180)
			(size 0.0762 0.0762)
			(layers "F.Cu" "F.Mask" "F.Paste")
			(net "SAS_HDD_TX1_N")
			(options
				(clearance outline)
				(anchor circle)
			)
			(primitives
				(gr_poly
					(pts
						(arc
							(start 0.1524 -0.127)
							(mid 0.137521 -0.162921)
							(end 0.1016 -0.1778)
						)
						(arc
							(start -0.1016 -0.1778)
							(mid -0.137521 -0.162921)
							(end -0.1524 -0.127)
						)
						(arc
							(start -0.1524 0.127)
							(mid -0.137521 0.162921)
							(end -0.1016 0.1778)
						)
						(arc
							(start 0.1016 0.1778)
							(mid 0.137521 0.162921)
							(end 0.1524 0.127)
						)
					)
					(width 0)
					(fill yes)
				)
			)
		)
		(pad "2" smd custom
			(at 0 0.2794 180)
			(size 0.0762 0.0762)
			(layers "F.Cu" "F.Mask" "F.Paste")
			(net "SAS_EXP_GF_TX_DN5")
			(options
				(clearance outline)
				(anchor circle)
			)
			(primitives
				(gr_poly
					(pts
						(arc
							(start 0.1524 -0.127)
							(mid 0.137521 -0.162921)
							(end 0.1016 -0.1778)
						)
						(arc
							(start -0.1016 -0.1778)
							(mid -0.137521 -0.162921)
							(end -0.1524 -0.127)
						)
						(arc
							(start -0.1524 0.127)
							(mid -0.137521 0.162921)
							(end -0.1016 0.1778)
						)
						(arc
							(start 0.1016 0.1778)
							(mid 0.137521 0.162921)
							(end 0.1524 0.127)
						)
					)
					(width 0)
					(fill yes)
				)
			)
		)
	)
	(footprint ""
		(layer "F.Cu")
		(at 251.11964 -50.039778)
		(property "Reference" "SC1065"
			(at 0 0 0)
			(layer "F.SilkS")
			(hide yes)
			(effects
				(font
					(size 1.27 1.27)
				)
			)
		)
		(property "Value" "SCD01U50V2KX-1GP"
			(at 1.1811 -2.7051 0)
			(unlocked yes)
			(layer "F.Fab")
			(hide yes)
			(effects
				(font
					(size 1.016 1.016)
					(thickness 0.1524)
				)
			)
		)
		(property "Device Type" "C402H22"
			(at 1.1811 -4.2291 0)
			(unlocked yes)
			(layer "F.Fab")
			(hide yes)
			(effects
				(font
					(size 1.016 1.016)
					(thickness 0.1524)
				)
			)
		)
		(duplicate_pad_numbers_are_jumpers no)
		(fp_rect
			(start -0.4318 0.9525)
			(end 0.4318 -0.9525)
			(stroke
				(width 0)
				(type default)
			)
			(fill no)
			(layer "F.CrtYd")
		)
		(fp_rect
			(start -0.4318 0.9525)
			(end 0.4318 -0.9525)
			(stroke
				(width 0)
				(type default)
			)
			(fill no)
			(layer "F.Fab")
		)
		(pad "1" smd custom
			(at 0 -0.4445)
			(size 0.1524 0.1524)
			(layers "F.Cu" "F.Mask" "F.Paste")
			(net "P1V8_C")
			(options
				(clearance outline)
				(anchor circle)
			)
			(primitives
				(gr_poly
					(pts
						(arc
							(start 0.3048 -0.2032)
							(mid 0.275042 -0.275042)
							(end 0.2032 -0.3048)
						)
						(arc
							(start -0.2032 -0.3048)
							(mid -0.275042 -0.275042)
							(end -0.3048 -0.2032)
						)
						(arc
							(start -0.3048 0.2032)
							(mid -0.275042 0.275042)
							(end -0.2032 0.3048)
						)
						(arc
							(start 0.2032 0.3048)
							(mid 0.275042 0.275042)
							(end 0.3048 0.2032)
						)
					)
					(width 0)
					(fill yes)
				)
			)
		)
		(pad "2" smd custom
			(at 0 0.4445)
			(size 0.1524 0.1524)
			(layers "F.Cu" "F.Mask" "F.Paste")
			(net "GND")
			(options
				(clearance outline)
				(anchor circle)
			)
			(primitives
				(gr_poly
					(pts
						(arc
							(start 0.3048 -0.2032)
							(mid 0.275042 -0.275042)
							(end 0.2032 -0.3048)
						)
						(arc
							(start -0.2032 -0.3048)
							(mid -0.275042 -0.275042)
							(end -0.3048 -0.2032)
						)
						(arc
							(start -0.3048 0.2032)
							(mid -0.275042 0.275042)
							(end -0.2032 0.3048)
						)
						(arc
							(start 0.2032 0.3048)
							(mid 0.275042 0.275042)
							(end 0.3048 0.2032)
						)
					)
					(width 0)
					(fill yes)
				)
			)
		)
	)
	(footprint ""
		(layer "F.Cu")
		(at 222.123 -25.781 -90)
		(property "Reference" "R7889"
			(at 0 0 270)
			(layer "F.SilkS")
			(hide yes)
			(effects
				(font
					(size 1.27 1.27)
				)
			)
		)
		(property "Value" "0R2J-2-GP"
			(at 0.064008 -3.993896 270)
			(unlocked yes)
			(layer "F.Fab")
			(hide yes)
			(effects
				(font
					(size 1.016 1.016)
					(thickness 0.1524)
				)
			)
		)
		(property "Device Type" "R402H16"
			(at 0.064008 -5.517896 270)
			(unlocked yes)
			(layer "F.Fab")
			(hide yes)
			(effects
				(font
					(size 1.016 1.016)
					(thickness 0.1524)
				)
			)
		)
		(duplicate_pad_numbers_are_jumpers no)
		(fp_line
			(start -0.508 -0.9398)
			(end -0.508 0.9398)
			(stroke
				(width 0.1524)
				(type default)
			)
			(layer "F.SilkS")
		)
		(fp_line
			(start 0.508 -0.9398)
			(end -0.508 -0.9398)
			(stroke
				(width 0.1524)
				(type default)
			)
			(layer "F.SilkS")
		)
		(fp_rect
			(start -0.508 0.9398)
			(end 0.508 -0.9398)
			(stroke
				(width 0)
				(type default)
			)
			(fill no)
			(layer "F.CrtYd")
		)
		(fp_rect
			(start -0.508 0.9398)
			(end 0.508 -0.9398)
			(stroke
				(width 0)
				(type default)
			)
			(fill no)
			(layer "F.Fab")
		)
		(pad "1" smd custom
			(at 0 -0.4445 270)
			(size 0.1397 0.1397)
			(layers "F.Cu" "F.Mask" "F.Paste")
			(net "BMC_ID_LED")
			(options
				(clearance outline)
				(anchor circle)
			)
			(primitives
				(gr_poly
					(pts
						(arc
							(start -0.1778 -0.2794)
							(mid -0.249642 -0.249642)
							(end -0.2794 -0.1778)
						)
						(arc
							(start -0.2794 0.1778)
							(mid -0.249642 0.249642)
							(end -0.1778 0.2794)
						)
						(arc
							(start 0.1778 0.2794)
							(mid 0.249642 0.249642)
							(end 0.2794 0.1778)
						)
						(arc
							(start 0.2794 -0.1778)
							(mid 0.249642 -0.249642)
							(end 0.1778 -0.2794)
						)
					)
					(width 0)
					(fill yes)
				)
			)
		)
		(pad "2" smd custom
			(at 0 0.4445 270)
			(size 0.1397 0.1397)
			(layers "F.Cu" "F.Mask" "F.Paste")
			(net "BMC_ID_LED_R")
			(options
				(clearance outline)
				(anchor circle)
			)
			(primitives
				(gr_poly
					(pts
						(arc
							(start -0.1778 -0.2794)
							(mid -0.249642 -0.249642)
							(end -0.2794 -0.1778)
						)
						(arc
							(start -0.2794 0.1778)
							(mid -0.249642 0.249642)
							(end -0.1778 0.2794)
						)
						(arc
							(start 0.1778 0.2794)
							(mid 0.249642 0.249642)
							(end 0.2794 0.1778)
						)
						(arc
							(start 0.2794 -0.1778)
							(mid 0.249642 -0.249642)
							(end 0.1778 -0.2794)
						)
					)
					(width 0)
					(fill yes)
				)
			)
		)
	)
	(footprint ""
		(layer "F.Cu")
		(at 193.167 -122.682 180)
		(property "Reference" "R602"
			(at 0 0 180)
			(layer "F.SilkS")
			(hide yes)
			(effects
				(font
					(size 1.27 1.27)
				)
			)
		)
		(property "Value" "4K7R2F-GP"
			(at 0.064008 -3.993896 180)
			(unlocked yes)
			(layer "F.Fab")
			(hide yes)
			(effects
				(font
					(size 1.016 1.016)
					(thickness 0.1524)
				)
			)
		)
		(property "Device Type" "R402H16"
			(at 0.064008 -5.517896 180)
			(unlocked yes)
			(layer "F.Fab")
			(hide yes)
			(effects
				(font
					(size 1.016 1.016)
					(thickness 0.1524)
				)
			)
		)
		(duplicate_pad_numbers_are_jumpers no)
		(fp_line
			(start 0.508 -0.9398)
			(end -0.508 -0.9398)
			(stroke
				(width 0.1524)
				(type default)
			)
			(layer "F.SilkS")
		)
		(fp_line
			(start -0.508 -0.9398)
			(end -0.508 0.9398)
			(stroke
				(width 0.1524)
				(type default)
			)
			(layer "F.SilkS")
		)
		(fp_rect
			(start -0.508 0.9398)
			(end 0.508 -0.9398)
			(stroke
				(width 0)
				(type default)
			)
			(fill no)
			(layer "F.CrtYd")
		)
		(fp_rect
			(start -0.508 0.9398)
			(end 0.508 -0.9398)
			(stroke
				(width 0)
				(type default)
			)
			(fill no)
			(layer "F.Fab")
		)
		(pad "1" smd custom
			(at 0 -0.4445 180)
			(size 0.1397 0.1397)
			(layers "F.Cu" "F.Mask" "F.Paste")
			(net "P1V8_E_B")
			(options
				(clearance outline)
				(anchor circle)
			)
			(primitives
				(gr_poly
					(pts
						(arc
							(start -0.1778 -0.2794)
							(mid -0.249642 -0.249642)
							(end -0.2794 -0.1778)
						)
						(arc
							(start -0.2794 0.1778)
							(mid -0.249642 0.249642)
							(end -0.1778 0.2794)
						)
						(arc
							(start 0.1778 0.2794)
							(mid 0.249642 0.249642)
							(end 0.2794 0.1778)
						)
						(arc
							(start 0.2794 -0.1778)
							(mid 0.249642 -0.249642)
							(end 0.1778 -0.2794)
						)
					)
					(width 0)
					(fill yes)
				)
			)
		)
		(pad "2" smd custom
			(at 0 0.4445 180)
			(size 0.1397 0.1397)
			(layers "F.Cu" "F.Mask" "F.Paste")
			(net "P1V8_E")
			(options
				(clearance outline)
				(anchor circle)
			)
			(primitives
				(gr_poly
					(pts
						(arc
							(start -0.1778 -0.2794)
							(mid -0.249642 -0.249642)
							(end -0.2794 -0.1778)
						)
						(arc
							(start -0.2794 0.1778)
							(mid -0.249642 0.249642)
							(end -0.1778 0.2794)
						)
						(arc
							(start 0.1778 0.2794)
							(mid 0.249642 0.249642)
							(end 0.2794 0.1778)
						)
						(arc
							(start 0.2794 -0.1778)
							(mid 0.249642 -0.249642)
							(end 0.1778 -0.2794)
						)
					)
					(width 0)
					(fill yes)
				)
			)
		)
	)
	(footprint ""
		(layer "F.Cu")
		(at 16.714216 -213.79688 180)
		(property "Reference" "R630"
			(at 0 0 180)
			(layer "F.SilkS")
			(hide yes)
			(effects
				(font
					(size 1.27 1.27)
				)
			)
		)
		(property "Value" "4K7R2F-GP"
			(at 0.064008 -3.993896 180)
			(unlocked yes)
			(layer "F.Fab")
			(hide yes)
			(effects
				(font
					(size 1.016 1.016)
					(thickness 0.1524)
				)
			)
		)
		(property "Device Type" "R402H16"
			(at 0.064008 -5.517896 180)
			(unlocked yes)
			(layer "F.Fab")
			(hide yes)
			(effects
				(font
					(size 1.016 1.016)
					(thickness 0.1524)
				)
			)
		)
		(duplicate_pad_numbers_are_jumpers no)
		(fp_line
			(start 0.508 -0.9398)
			(end -0.508 -0.9398)
			(stroke
				(width 0.1524)
				(type default)
			)
			(layer "F.SilkS")
		)
		(fp_line
			(start -0.508 -0.9398)
			(end -0.508 0.9398)
			(stroke
				(width 0.1524)
				(type default)
			)
			(layer "F.SilkS")
		)
		(fp_rect
			(start -0.508 0.9398)
			(end 0.508 -0.9398)
			(stroke
				(width 0)
				(type default)
			)
			(fill no)
			(layer "F.CrtYd")
		)
		(fp_rect
			(start -0.508 0.9398)
			(end 0.508 -0.9398)
			(stroke
				(width 0)
				(type default)
			)
			(fill no)
			(layer "F.Fab")
		)
		(pad "1" smd custom
			(at 0 -0.4445 180)
			(size 0.1397 0.1397)
			(layers "F.Cu" "F.Mask" "F.Paste")
			(net "P3V3_STBY")
			(options
				(clearance outline)
				(anchor circle)
			)
			(primitives
				(gr_poly
					(pts
						(arc
							(start -0.1778 -0.2794)
							(mid -0.249642 -0.249642)
							(end -0.2794 -0.1778)
						)
						(arc
							(start -0.2794 0.1778)
							(mid -0.249642 0.249642)
							(end -0.1778 0.2794)
						)
						(arc
							(start 0.1778 0.2794)
							(mid 0.249642 0.249642)
							(end 0.2794 0.1778)
						)
						(arc
							(start 0.2794 -0.1778)
							(mid 0.249642 -0.249642)
							(end 0.1778 -0.2794)
						)
					)
					(width 0)
					(fill yes)
				)
			)
		)
		(pad "2" smd custom
			(at 0 0.4445 180)
			(size 0.1397 0.1397)
			(layers "F.Cu" "F.Mask" "F.Paste")
			(net "IO_EXP_HDD_PWR_A0")
			(options
				(clearance outline)
				(anchor circle)
			)
			(primitives
				(gr_poly
					(pts
						(arc
							(start -0.1778 -0.2794)
							(mid -0.249642 -0.249642)
							(end -0.2794 -0.1778)
						)
						(arc
							(start -0.2794 0.1778)
							(mid -0.249642 0.249642)
							(end -0.1778 0.2794)
						)
						(arc
							(start 0.1778 0.2794)
							(mid 0.249642 0.249642)
							(end 0.2794 0.1778)
						)
						(arc
							(start 0.2794 -0.1778)
							(mid 0.249642 -0.249642)
							(end 0.1778 -0.2794)
						)
					)
					(width 0)
					(fill yes)
				)
			)
		)
	)
)
